FILE_TYPE = CONNECTIVITY;
{Allegro Design Entry HDL 17.2-2016 S081 (4005846) 1/11/2022}
"PAGE_NUMBER" = 245;
0"NC";
1"P12V_AUX\g";
2"P12V_AUX\g";
3"P12V_AUX\g";
4"P3V3_AUX\g";
5"P3V3_AUX\g";
6"P3V3_AUX\g";
7"GND\g";
8"GND\g";
9"GND\g";
10"GND\g";
11"GND\g";
12"GND\g";
13"GND\g";
14"GND\g";
15"GND\g";
16"GND\g";
17"GND\g";
18"GND\g";
19"GND\g";
20"GND\g";
21"GND\g";
22"P3V3_AUX_EN";
23"NC_PU9_1";
24"MB0_P12V_STBY_PWRGD";
25"P3V3_AUX_MODE";
26"P3V3_AUX_FB";
27"SW_P3V3_AUX_BOOT_R";
28"SW_P3V3_AUX_SW";
29"SW_P3V3_AUX_BOOTR";
30"PWRGD_P3V3_AUX";
31"SW_P3V3_AUX_BOOT";
32"P3V3_AUX_VOS";
33"SW_P3V3_AUX_FLT";
34"P3V3_AUX_VCC";
35"NC_PU9_3";
36"NC_PU9_4";
37"NC_HICCUP";
38"NC_PU9_2";
39"P3V3_AUX_VDRV";
40"P3V3_AUX_ILIM";
41"P3V3_AUX_SS";
%"Q_CAP"
"1","(-4050,200)","0","pure_quanta","I100";
;
PART_NUMBER"CH6223MEA01"
VALUE"22UF"
VOLTAGE"16V"
MATERIAL"X6S"
PACK_TYPE"C0805"
TOLERANCE"20%"
LOCATION"PC2260"
CDS_LIB"pure_quanta"
$SEC"1"
CDS_SEC"1";
"B"
$PN"2"9;
"A"
$PN"1"33;
%"Q_CAP"
"1","(-3725,200)","0","pure_quanta","I101";
;
PART_NUMBER"CH6223MEA01"
VOLTAGE"16V"
MATERIAL"X6S"
VALUE"22UF"
PACK_TYPE"C0805"
TOLERANCE"20%"
LOCATION"PC2261"
CDS_LIB"pure_quanta"
$SEC"1"
CDS_SEC"1";
"B"
$PN"2"9;
"A"
$PN"1"33;
%"GND"
"1","(-3975,475)","0","logical_power","I102";
;
HDL_POWER"GND"
CDS_LIB"logical_power"
SIZE"1B";
"A<SIZE-1..0>\NAC"16;
%"Q_CAPP"
"1","(-3975,850)","0","pure_quanta","I103";
;
PART_NUMBER"CC72703MD38"
VALUE"270UF"
PACK_TYPE"THLF"
MATERIAL"OSCON"
VOLTAGE"16V"
TOLERANCE"20%"
LOCATION"PC3"
CDS_LIB"pure_quanta"
LOCATION"PC3"
$SEC"1"
CDS_SEC"1";
"A"
$PN"1"33;
"B"
$PN"2"16;
%"Q_CAPP"
"1","(-3675,850)","0","pure_quanta","I104";
;
PART_NUMBER"CC72703MD38"
TOLERANCE"20%"
VALUE"270UF"
PACK_TYPE"THLF"
VOLTAGE"16V"
MATERIAL"OSCON"
LOCATION"PC566"
CDS_LIB"pure_quanta"
LOCATION"PC566"
$SEC"1"
CDS_SEC"1";
"A"
$PN"1"33;
"B"
$PN"2"16;
%"Q_CAP"
"1","(-3400,200)","0","pure_quanta","I105";
;
PART_NUMBER"CH6223MEA01"
VALUE"22UF"
PACK_TYPE"C0805"
VOLTAGE"16V"
TOLERANCE"20%"
MATERIAL"X6S"
LOCATION"PC2262"
CDS_LIB"pure_quanta"
$SEC"1"
CDS_SEC"1";
"B"
$PN"2"9;
"A"
$PN"1"33;
%"Q_CAP"
"1","(-3350,850)","0","pure_quanta","I106";
;
PART_NUMBER"CH6223MEA01"
MATERIAL"X6S"
TOLERANCE"20%"
PACK_TYPE"C0805"
VOLTAGE"16V"
VALUE"22UF"
LOCATION"PC567"
CDS_LIB"pure_quanta"
$SEC"1"
CDS_SEC"1";
"B"
$PN"2"16;
"A"
$PN"1"33;
%"Q_CAP"
"1","(-3075,200)","0","pure_quanta","I107";
;
PART_NUMBER"CH6223MEA01"
PACK_TYPE"C0805"
VALUE"22UF"
VOLTAGE"16V"
TOLERANCE"20%"
MATERIAL"X6S"
LOCATION"PC2263"
CDS_LIB"pure_quanta"
$SEC"1"
CDS_SEC"1";
"B"
$PN"2"9;
"A"
$PN"1"33;
%"Q_CAP"
"1","(-2750,200)","0","pure_quanta","I108";
;
PART_NUMBER"CH6223MEA01"
PACK_TYPE"C0805"
VALUE"22UF"
VOLTAGE"16V"
MATERIAL"X6S"
TOLERANCE"20%"
LOCATION"PC2342"
CDS_LIB"pure_quanta"
$SEC"1"
CDS_SEC"1";
"B"
$PN"2"9;
"A"
$PN"1"33;
%"Q_CAP"
"1","(-3025,850)","0","pure_quanta","I109";
;
PART_NUMBER"CH6223MEA01"
PACK_TYPE"C0805"
VALUE"22UF"
MATERIAL"X6S"
VOLTAGE"16V"
TOLERANCE"20%"
LOCATION"PC570"
CDS_LIB"pure_quanta"
$SEC"1"
CDS_SEC"1";
"B"
$PN"2"16;
"A"
$PN"1"33;
%"Q_CAP"
"1","(-2700,850)","0","pure_quanta","I110";
;
PART_NUMBER"CH6223MEA01"
VALUE"22UF"
MATERIAL"X6S"
VOLTAGE"16V"
TOLERANCE"20%"
PACK_TYPE"C0805"
LOCATION"PC571"
CDS_LIB"pure_quanta"
$SEC"1"
CDS_SEC"1";
"B"
$PN"2"16;
"A"
$PN"1"33;
%"Q_CAP"
"1","(-2425,200)","0","pure_quanta","I111";
;
PART_NUMBER"CH6223MEA01"
PACK_TYPE"C0805"
VOLTAGE"16V"
VALUE"22UF"
TOLERANCE"20%"
MATERIAL"X6S"
LOCATION"PC2343"
CDS_LIB"pure_quanta"
$SEC"1"
CDS_SEC"1";
"B"
$PN"2"9;
"A"
$PN"1"33;
%"Q_CAP"
"1","(-2100,200)","0","pure_quanta","I112";
;
PART_NUMBER"CH6223MEA01"
PACK_TYPE"C0805"
TOLERANCE"20%"
MATERIAL"X6S"
VOLTAGE"16V"
VALUE"22UF"
LOCATION"PC2344"
CDS_LIB"pure_quanta"
$SEC"1"
CDS_SEC"1";
"B"
$PN"2"9;
"A"
$PN"1"33;
%"Q_CAP"
"1","(-2375,850)","0","pure_quanta","I113";
;
PART_NUMBER"CH6223MEA01"
MATERIAL"X6S"
PACK_TYPE"C0805"
VOLTAGE"16V"
VALUE"22UF"
TOLERANCE"20%"
LOCATION"PC576"
CDS_LIB"pure_quanta"
$SEC"1"
CDS_SEC"1";
"B"
$PN"2"16;
"A"
$PN"1"33;
%"Q_CAP"
"1","(-2050,850)","0","pure_quanta","I114";
;
PART_NUMBER"CH6223MEA01"
TOLERANCE"20%"
MATERIAL"X6S"
VALUE"22UF"
PACK_TYPE"C0805"
VOLTAGE"16V"
LOCATION"PC71"
CDS_LIB"pure_quanta"
$SEC"1"
CDS_SEC"1";
"B"
$PN"2"16;
"A"
$PN"1"33;
%"Q_CAP"
"1","(-1725,850)","0","pure_quanta","I115";
;
PART_NUMBER"CH4104K1B00"
VALUE"0.1UF"
VOLTAGE"25V"
TOLERANCE"10%"
MATERIAL"X7R"
PACK_TYPE"0402"
LOCATION"PC577"
CDS_LIB"pure_quanta"
$SEC"1"
CDS_SEC"1";
"B"
$PN"2"16;
"A"
$PN"1"33;
%"UNIVERSAL_POWER"
"1","(-1150,800)","0","logical_power","I116";
;
HDL_POWER"P12V_AUX"
CDS_LIB"logical_power";
"A"3;
%"GND"
"1","(-900,200)","0","logical_power","I117";
;
HDL_POWER"GND"
SIZE"1B"
CDS_LIB"logical_power";
"A<SIZE-1..0>\NAC"17;
%"Q_CAP"
"1","(-900,475)","0","pure_quanta","I118";
;
PART_NUMBER"CH5473KE902"
VOLTAGE"16V"
PACK_TYPE"C0603"
MATERIAL"X6S"
VALUE"4.7UF"
TOLERANCE"10%"
LOCATION"PC8"
CDS_LIB"pure_quanta"
$SEC"1"
CDS_SEC"1";
"B"
$PN"2"17;
"A"
$PN"1"3;
%"GND"
"1","(350,-1500)","0","logical_power","I119";
;
HDL_POWER"GND"
CDS_LIB"logical_power"
SIZE"1B";
"A<SIZE-1..0>\NAC"18;
%"GND"
"1","(550,-1200)","1","logical_power","I120";
;
HDL_POWER"GND"
CDS_LIB"logical_power"
SIZE"1B";
"A<SIZE-1..0>\NAC"19;
%"Q_RES"
"1","(825,-1250)","0","pure_quanta","I121";
;
PART_NUMBER"CS21002FB06"
MATERIAL"EMPTY"
WATTAGE"1/16W"
VALUE"1K"
PACK_TYPE"0402LF"
TOLERANCE"1%"
LOCATION"PR836"
CDS_LIB"pure_quanta"
$SEC"1"
CDS_SEC"1";
"B"
$PN"2"4;
"A"
$PN"1"32;
%"Q_CAP"
"2","(725,-550)","0","pure_quanta","I122";
;
PART_NUMBER"CH4224K1B01"
VOLTAGE"25V"
MATERIAL"X7R"
TOLERANCE"10%"
VALUE"0.22UF"
LOCATION"PC568"
CDS_LIB"pure_quanta"
PACK_TYPE"C0402"
$SEC"1"
CDS_SEC"1";
"A"
$PN"1"29;
"B"
$PN"2"27;
%"Q_RES"
"1","(800,-350)","0","pure_quanta","I123";
;
PART_NUMBER"CS00002JB13"
WATTAGE"1/16W"
PACK_TYPE"0402LF"
TOLERANCE"5%"
VALUE"0"
MATERIAL"CHIP"
LOCATION"PR835"
CDS_LIB"pure_quanta"
$SEC"1"
CDS_SEC"1";
"B"
$PN"2"27;
"A"
$PN"1"31;
%"GND"
"1","(1200,-2000)","0","logical_power","I124";
;
HDL_POWER"GND"
SIZE"1B"
CDS_LIB"logical_power";
"A<SIZE-1..0>\NAC"20;
%"Q_RES"
"2","(1200,-1725)","0","pure_quanta","I125";
;
PART_NUMBER"CS31502BB03"
TOLERANCE"0.1%"
VALUE"15K"
PACK_TYPE"0402LF"
WATTAGE"1/16W"
MATERIAL"CHIP"
LOCATION"PR830"
CDS_LIB"pure_quanta"
$SEC"1"
CDS_SEC"1";
"A"
$PN"1"26;
"B"
$PN"2"20;
%"UNIVERSAL_POWER"
"1","(1075,-1150)","0","logical_power","I126";
;
HDL_POWER"P3V3_AUX"
CDS_LIB"logical_power";
"A"4;
%"Q_CAP"
"2","(2100,-1850)","0","pure_quanta","I127";
;
PART_NUMBER"TMP_QCH12206KB14"
PACK_TYPE"0402"
VALUE"220PF"
TOLERANCE"10%"
MATERIAL"X7R"
VOLTAGE"50V"
LOCATION"PC569"
CDS_LIB"pure_quanta"
$SEC"1"
CDS_SEC"1";
"A"
$PN"1"26;
"B"
$PN"2"5;
%"Q_RES"
"1","(2100,-1550)","0","pure_quanta","I128";
;
PART_NUMBER"CS34702BB05"
PACK_TYPE"0402LF"
WATTAGE"1/16W"
VALUE"47K"
MATERIAL"CHIP"
TOLERANCE"0.1%"
LOCATION"PR831"
CDS_LIB"pure_quanta"
$SEC"1"
CDS_SEC"1";
"B"
$PN"2"5;
"A"
$PN"1"26;
%"Q_INDUCTOR"
"1","(1425,-725)","0","pure_quanta","I129";
;
PART_NUMBER"CV-15^0MZ02"
MATERIAL"IND"
VALUE"1.5UH/53A"
PACK_TYPE"SMLF"
LOCATION"PL66"
NEEDS_NO_SIZE"TRUE"
CDS_LIB"pure_quanta"
$SEC"1"
CDS_SEC"1";
"1"
$PN"1"28;
"2"
$PN"2"5;
%"Q_CAPP"
"1","(1650,-975)","0","pure_quanta","I131";
;
PART_NUMBER"CC75601MD16"
VALUE"560UF"
MATERIAL"OSCON"
VOLTAGE"6.3V"
TOLERANCE"20%"
PACK_TYPE"THLF"
LOCATION"PC1866"
CDS_LIB"pure_quanta"
$SEC"1"
CDS_SEC"1";
"A"
$PN"1"5;
"B"
$PN"2"21;
%"Q_CAPP"
"1","(2100,-975)","0","pure_quanta","I132";
;
PART_NUMBER"CC75601MD16"
PACK_TYPE"THLF"
MATERIAL"OSCON"
VOLTAGE"6.3V"
TOLERANCE"20%"
VALUE"560UF"
LOCATION"PC1867"
CDS_LIB"pure_quanta"
$SEC"1"
CDS_SEC"1";
"A"
$PN"1"5;
"B"
$PN"2"21;
%"Q_CAP"
"1","(2550,-950)","0","pure_quanta","I133";
;
PART_NUMBER"CH6222MEA01"
MATERIAL"X6S"
VOLTAGE"10V"
TOLERANCE"20%"
PACK_TYPE"C0805"
VALUE"22UF"
LOCATION"PC1868"
CDS_LIB"pure_quanta"
$SEC"1"
CDS_SEC"1";
"B"
$PN"2"21;
"A"
$PN"1"5;
%"Q_CAP"
"1","(2950,-975)","0","pure_quanta","I134";
;
PART_NUMBER"CH6222MEA01"
VALUE"22UF"
VOLTAGE"10V"
TOLERANCE"20%"
MATERIAL"X6S"
PACK_TYPE"C0805"
LOCATION"PC1599"
CDS_LIB"pure_quanta"
$SEC"1"
CDS_SEC"1";
"B"
$PN"2"21;
"A"
$PN"1"5;
%"GND"
"1","(3725,-1350)","0","logical_power","I135";
;
HDL_POWER"GND"
SIZE"1B"
CDS_LIB"logical_power";
"A<SIZE-1..0>\NAC"21;
%"Q_CAP"
"1","(3325,-975)","0","pure_quanta","I136";
;
PART_NUMBER"CH6222MEA01"
VOLTAGE"10V"
TOLERANCE"20%"
MATERIAL"X6S"
PACK_TYPE"C0805"
VALUE"22UF"
LOCATION"PC1600"
CDS_LIB"pure_quanta"
$SEC"1"
CDS_SEC"1";
"B"
$PN"2"21;
"A"
$PN"1"5;
%"Q_CAP"
"1","(3725,-975)","0","pure_quanta","I137";
;
PART_NUMBER"CH4104K1B00"
TOLERANCE"10%"
PACK_TYPE"0402"
VALUE"0.1UF"
MATERIAL"X7R"
VOLTAGE"25V"
LOCATION"PC1869"
CDS_LIB"pure_quanta"
$SEC"1"
CDS_SEC"1";
"B"
$PN"2"21;
"A"
$PN"1"5;
%"UNIVERSAL_POWER"
"1","(4175,-450)","0","logical_power","I138";
;
HDL_POWER"P3V3_AUX"
CDS_LIB"logical_power";
"A"5;
%"Q_RES"
"2","(900,200)","0","pure_quanta","I139";
;
PART_NUMBER"CS31002FB08"
PACK_TYPE"0402LF"
TOLERANCE"1%"
VALUE"10K"
WATTAGE"1/16W"
MATERIAL"CHIP"
LOCATION"PR73"
CDS_LIB"pure_quanta"
$SEC"1"
CDS_SEC"1";
"A"
$PN"1"6;
"B"
$PN"2"30;
%"UNIVERSAL_POWER"
"1","(900,425)","0","logical_power","I140";
;
HDL_POWER"P3V3_AUX"
CDS_LIB"logical_power";
"A"6;
%"Q_DIODE"
"1","(-3025,-775)","0","pure_quanta","I71";
;
PART_NUMBER"BC000340033"
PACK_TYPE"SMLF"
VALUE"SDMK0340L-7-F"
MATERIAL"IC"
$LOCATION"D145"
CDS_LIB"pure_quanta"
PIN_NAMES_ROTATE"True"
NEEDS_NO_SIZE"TRUE"
CDS_LOCATION"D145"
$SEC"1"
CDS_SEC"1";
"1"
$PN"1"24;
"2"
$PN"2"22;
%"Q_RES"
"2","(-3275,-1025)","0","pure_quanta","I72";
;
PART_NUMBER"CS41002FB09"
TOLERANCE"1%"
PACK_TYPE"0402LF"
MATERIAL"CHIP"
WATTAGE"1/16W"
VALUE"100K"
LOCATION"R1571"
CDS_LIB"pure_quanta"
$SEC"1"
CDS_SEC"1";
"A"
$PN"1"24;
"B"
$PN"2"22;
%"Q_CAP"
"1","(-3225,-1600)","0","pure_quanta","I73";
;
PART_NUMBER"CH4224K1B01"
VOLTAGE"25V"
PACK_TYPE"C0402"
VALUE"0.22UF"
MATERIAL"X7R"
TOLERANCE"10%"
LOCATION"C2541"
CDS_LIB"pure_quanta"
$SEC"1"
CDS_SEC"1";
"B"
$PN"2"8;
"A"
$PN"1"22;
%"GND"
"1","(-3225,-1900)","0","logical_power","I74";
;
SIZE"1B"
CDS_LIB"logical_power"
HDL_POWER"GND";
"A<SIZE-1..0>\NAC"8;
%"GND"
"1","(-3825,-1825)","0","logical_power","I75";
;
HDL_POWER"GND"
SIZE"1B"
CDS_LIB"logical_power";
"A<SIZE-1..0>\NAC"7;
%"Q_RES"
"2","(-3825,-1525)","0","pure_quanta","I76";
;
PART_NUMBER"CS38662FB05"
PACK_TYPE"0402LF"
MATERIAL"EMPTY"
WATTAGE"1/16W"
VALUE"86.6K"
TOLERANCE"1%"
$LOCATION"R3118"
CDS_LIB"pure_quanta"
CDS_LOCATION"R3118"
$SEC"1"
CDS_SEC"1";
"A"
$PN"1"22;
"B"
$PN"2"7;
%"GND"
"1","(-4050,-150)","0","logical_power","I77";
;
HDL_POWER"GND"
CDS_LIB"logical_power"
SIZE"1B";
"A<SIZE-1..0>\NAC"9;
%"Q_RES"
"2","(-3825,-950)","0","pure_quanta","I78";
;
PART_NUMBER"CS45102JB03"
WATTAGE"1/16W"
MATERIAL"EMPTY"
TOLERANCE"5%"
VALUE"510K"
PACK_TYPE"0402LF"
$LOCATION"R3117"
CDS_LIB"pure_quanta"
CDS_LOCATION"R3117"
$SEC"1"
CDS_SEC"1";
"A"
$PN"1"1;
"B"
$PN"2"22;
%"P1V0_AUX"
"1","(-3825,-625)","0","logical_power","I80";
;
HDL_POWER"P12V_AUX"
ROOM"VR_DDR1_POWER_STAGE"
CDS_LIB"logical_power";
"A"1;
%"GND"
"1","(-2150,-1400)","0","logical_power","I83";
;
HDL_POWER"GND"
CDS_LIB"logical_power"
SIZE"1B";
"A<SIZE-1..0>\NAC"10;
%"Q_RES"
"2","(-2150,-1225)","0","pure_quanta","I84";
;
PART_NUMBER"CS00002JB13"
MATERIAL"CHIP"
TOLERANCE"5%"
WATTAGE"1/16W"
VALUE"0"
PACK_TYPE"0402LF"
LOCATION"PR832"
CDS_LIB"pure_quanta"
$SEC"1"
CDS_SEC"1";
"A"
$PN"1"25;
"B"
$PN"2"10;
%"Q_CAP"
"1","(-2050,-625)","0","pure_quanta","I86";
;
PART_NUMBER"CH5473KE902"
PACK_TYPE"C0603"
VALUE"4.7UF"
VOLTAGE"16V"
TOLERANCE"10%"
MATERIAL"X6S"
LOCATION"PC581"
CDS_LIB"pure_quanta"
$SEC"1"
CDS_SEC"1";
"B"
$PN"2"11;
"A"
$PN"1"39;
%"GND"
"1","(-2050,-850)","0","logical_power","I87";
;
HDL_POWER"GND"
CDS_LIB"logical_power"
SIZE"1B";
"A<SIZE-1..0>\NAC"11;
%"GND"
"1","(-1750,-1525)","0","logical_power","I88";
;
HDL_POWER"GND"
SIZE"1B"
CDS_LIB"logical_power";
"A<SIZE-1..0>\NAC"12;
%"Q_RES"
"2","(-1750,-1325)","0","pure_quanta","I89";
;
PART_NUMBER"CS21502FB07"
TOLERANCE"1%"
VALUE"1.5K"
PACK_TYPE"0402LF"
MATERIAL"EMPTY"
WATTAGE"1/16W"
LOCATION"PR833"
CDS_LIB"pure_quanta"
$SEC"1"
CDS_SEC"1";
"A"
$PN"1"41;
"B"
$PN"2"12;
%"GND"
"1","(-1350,-1625)","0","logical_power","I90";
;
HDL_POWER"GND"
CDS_LIB"logical_power"
SIZE"1B";
"A<SIZE-1..0>\NAC"13;
%"Q_RES"
"2","(-1350,-1425)","0","pure_quanta","I91";
;
PART_NUMBER"CS32152FB04"
PACK_TYPE"0402LF"
MATERIAL"CHIP"
TOLERANCE"1%"
WATTAGE"1/16W"
VALUE"21.5K"
LOCATION"PR834"
CDS_LIB"pure_quanta"
$SEC"1"
CDS_SEC"1";
"A"
$PN"1"40;
"B"
$PN"2"13;
%"GND"
"1","(-1625,-850)","0","logical_power","I92";
;
HDL_POWER"GND"
SIZE"1B"
CDS_LIB"logical_power";
"A<SIZE-1..0>\NAC"14;
%"Q_CAP"
"1","(-1625,-625)","0","pure_quanta","I93";
;
PART_NUMBER"CH5223KE901"
PACK_TYPE"C0603"
MATERIAL"X6S"
VOLTAGE"16V"
VALUE"2.2UF"
TOLERANCE"10%"
LOCATION"PC591"
CDS_LIB"pure_quanta"
$SEC"1"
CDS_SEC"1";
"B"
$PN"2"14;
"A"
$PN"1"34;
%"Q_RES"
"1","(-1800,-400)","0","pure_quanta","I94";
;
PART_NUMBER"CS-1002FB04"
TOLERANCE"1%"
VALUE"1"
MATERIAL"CHIP"
PACK_TYPE"0402LF"
WATTAGE"1/16W"
LOCATION"PR389"
CDS_LIB"pure_quanta"
$SEC"1"
CDS_SEC"1";
"B"
$PN"2"34;
"A"
$PN"1"39;
%"IR3889MTRPBF"
"1","(-100,-750)","0","pure_quanta","I95";
;
PART_NUMBER"AL003889000"
MATERIAL"IC"
VALUE"IR3889MTRPBF"
PART_TYPE"SMLF"
LOCATION"PU9"
SEC_TYPE""
CDS_LIB"pure_quanta"
NEEDS_NO_SIZE"TRUE"
CDS_LMAN_SYM_OUTLINE"-300,700,250,-700"
SEC"1";
"GATEL2"
$PN"37"36;
"SS||LATCH"
$PN"29"41;
"GATEL1"
$PN"6"35;
"VDRV"
$PN"5"39;
"EN"
$PN"27"22;
"AGND"
$PN"32"18;
"NC1"
$PN"28"32;
"PGOOD"
$PN"2"30;
"PVIN"
$PN"20_24"33;
"SW"
$PN"11_18"28;
"NC2"
$PN"33"23;
"PGND"
$PN"7_10-19"18;
"NC4"
$PN"35"37;
"VSENM"
$PN"31"19;
"VCC||LDO"
$PN"4"34;
"PHASE"
$PN"25"29;
"ILIM"
$PN"1"40;
"BOOT"
$PN"26"31;
"FB"
$PN"30"26;
"VIN"
$PN"3"3;
"TON||MODE"
$PN"36"25;
"NC3"
$PN"34"38;
%"GND"
"1","(-4525,600)","0","logical_power","I96";
;
HDL_POWER"GND"
SIZE"1B"
CDS_LIB"logical_power";
"A<SIZE-1..0>\NAC"15;
%"Q_CAP"
"1","(-4525,850)","0","pure_quanta","I97";
;
PART_NUMBER"CH4106K1B01"
VOLTAGE"50V"
VALUE"100NF"
TOLERANCE"10%"
MATERIAL"X7R"
PACK_TYPE"C0402"
LOCATION"PC1649"
CDS_LIB"pure_quanta"
$SEC"1"
CDS_SEC"1";
"B"
$PN"2"15;
"A"
$PN"1"2;
%"Q_INDUCTOR"
"1","(-4300,1075)","0","pure_quanta","I98";
;
PART_NUMBER"CV+10G0MZ04"
MATERIAL"IND"
VALUE"100NH/16A"
PACK_TYPE"SMLF"
LOCATION"PL45"
NEEDS_NO_SIZE"TRUE"
CDS_LIB"pure_quanta"
$SEC"1"
CDS_SEC"1";
"1"
$PN"1"2;
"2"
$PN"2"33;
%"UNIVERSAL_POWER"
"1","(-4525,1475)","0","logical_power","I99";
;
HDL_POWER"P12V_AUX"
CDS_LIB"logical_power";
"A"2;
END.
